(kicad_pcb
	(version 20260206)
	(generator "pcbnew")
	(generator_version "10.0")
	(general
		(thickness 1.6)
		(legacy_teardrops no)
	)
	(paper "A4")
	(title_block
		(title "peb — Lightning_PEB_BRD.brd")
		(comment 1 "Lightning (Wiwynn / Facebook NVMe JBOF) / footprints 1307-1311 of 2563")
	)
	(layers
		(0 "F.Cu" signal "TOP")
		(4 "In1.Cu" signal "L2GND")
		(6 "In2.Cu" signal "L3")
		(8 "In3.Cu" signal "L4VCC")
		(10 "In4.Cu" signal "L5VCC")
		(12 "In5.Cu" signal "L6")
		(14 "In6.Cu" signal "L7GND")
		(2 "B.Cu" signal "BOTTOM")
		(9 "F.Adhes" user "F.Adhesive")
		(11 "B.Adhes" user "B.Adhesive")
		(13 "F.Paste" user "Package Geometry/Pastemask Top")
		(15 "B.Paste" user "Package Geometry/Pastemask Bottom")
		(5 "F.SilkS" user "Ref Des/Silkscreen Top")
		(7 "B.SilkS" user "Ref Des/Silkscreen Bottom")
		(1 "F.Mask" user "Board Geometry/Soldermask Top")
		(3 "B.Mask" user "Board Geometry/Soldermask Bottom")
		(17 "Dwgs.User" user "User.Drawings")
		(19 "Cmts.User" user "User.Comments")
		(21 "Eco1.User" user "User.Eco1")
		(23 "Eco2.User" user "User.Eco2")
		(25 "Edge.Cuts" user "Board Geometry/Outline")
		(27 "Margin" user)
		(31 "F.CrtYd" user "Package Geometry/Place Bound Top")
		(29 "B.CrtYd" user "Package Geometry/Place Bound Bottom")
		(35 "F.Fab" user "Ref Des/Assembly Top")
		(33 "B.Fab" user "Ref Des/Assembly Bottom")
	)
	(footprint ""
		(layer "F.Cu")
		(at 77.216 -197.6628 180)
		(property "Reference" "R7978"
			(at 0 0 180)
			(layer "F.SilkS")
			(hide yes)
			(effects
				(font
					(size 1.27 1.27)
				)
			)
		)
		(property "Value" "0R2J-2-GP"
			(at 0.064008 -3.993896 180)
			(unlocked yes)
			(layer "F.Fab")
			(hide yes)
			(effects
				(font
					(size 1.016 1.016)
					(thickness 0.1524)
				)
			)
		)
		(property "Device Type" "R402H16"
			(at 0.064008 -5.517896 180)
			(unlocked yes)
			(layer "F.Fab")
			(hide yes)
			(effects
				(font
					(size 1.016 1.016)
					(thickness 0.1524)
				)
			)
		)
		(duplicate_pad_numbers_are_jumpers no)
		(fp_line
			(start 0.508 -0.9398)
			(end -0.508 -0.9398)
			(stroke
				(width 0.1524)
				(type default)
			)
			(layer "F.SilkS")
		)
		(fp_line
			(start -0.508 -0.9398)
			(end -0.508 0.9398)
			(stroke
				(width 0.1524)
				(type default)
			)
			(layer "F.SilkS")
		)
		(fp_rect
			(start -0.508 0.9398)
			(end 0.508 -0.9398)
			(stroke
				(width 0)
				(type default)
			)
			(fill no)
			(layer "F.CrtYd")
		)
		(fp_rect
			(start -0.508 0.9398)
			(end 0.508 -0.9398)
			(stroke
				(width 0)
				(type default)
			)
			(fill no)
			(layer "F.Fab")
		)
		(pad "1" smd custom
			(at 0 -0.4445 180)
			(size 0.1397 0.1397)
			(layers "F.Cu" "F.Mask" "F.Paste")
			(net "SSD_PERST#10")
			(options
				(clearance outline)
				(anchor circle)
			)
			(primitives
				(gr_poly
					(pts
						(arc
							(start -0.1778 -0.2794)
							(mid -0.249642 -0.249642)
							(end -0.2794 -0.1778)
						)
						(arc
							(start -0.2794 0.1778)
							(mid -0.249642 0.249642)
							(end -0.1778 0.2794)
						)
						(arc
							(start 0.1778 0.2794)
							(mid 0.249642 0.249642)
							(end 0.2794 0.1778)
						)
						(arc
							(start 0.2794 -0.1778)
							(mid 0.249642 -0.249642)
							(end 0.1778 -0.2794)
						)
					)
					(width 0)
					(fill yes)
				)
			)
		)
		(pad "2" smd custom
			(at 0 0.4445 180)
			(size 0.1397 0.1397)
			(layers "F.Cu" "F.Mask" "F.Paste")
			(net "SSD_PERST#10_R")
			(options
				(clearance outline)
				(anchor circle)
			)
			(primitives
				(gr_poly
					(pts
						(arc
							(start -0.1778 -0.2794)
							(mid -0.249642 -0.249642)
							(end -0.2794 -0.1778)
						)
						(arc
							(start -0.2794 0.1778)
							(mid -0.249642 0.249642)
							(end -0.1778 0.2794)
						)
						(arc
							(start 0.1778 0.2794)
							(mid 0.249642 0.249642)
							(end 0.2794 0.1778)
						)
						(arc
							(start 0.2794 -0.1778)
							(mid 0.249642 -0.249642)
							(end 0.1778 -0.2794)
						)
					)
					(width 0)
					(fill yes)
				)
			)
		)
	)
	(footprint ""
		(layer "F.Cu")
		(at 123.18238 -6.78688 90)
		(property "Reference" "SR710"
			(at 0 0 90)
			(layer "F.SilkS")
			(hide yes)
			(effects
				(font
					(size 1.27 1.27)
				)
			)
		)
		(property "Value" "150R2F-1-GP"
			(at 0.064008 -3.993896 90)
			(unlocked yes)
			(layer "F.Fab")
			(hide yes)
			(effects
				(font
					(size 1.016 1.016)
					(thickness 0.1524)
				)
			)
		)
		(property "Device Type" "R402H16"
			(at 0.064008 -5.517896 90)
			(unlocked yes)
			(layer "F.Fab")
			(hide yes)
			(effects
				(font
					(size 1.016 1.016)
					(thickness 0.1524)
				)
			)
		)
		(duplicate_pad_numbers_are_jumpers no)
		(fp_line
			(start 0.508 -0.9398)
			(end -0.508 -0.9398)
			(stroke
				(width 0.1524)
				(type default)
			)
			(layer "F.SilkS")
		)
		(fp_line
			(start -0.508 -0.9398)
			(end -0.508 0.9398)
			(stroke
				(width 0.1524)
				(type default)
			)
			(layer "F.SilkS")
		)
		(fp_rect
			(start -0.508 0.9398)
			(end 0.508 -0.9398)
			(stroke
				(width 0)
				(type default)
			)
			(fill no)
			(layer "F.CrtYd")
		)
		(fp_rect
			(start -0.508 0.9398)
			(end 0.508 -0.9398)
			(stroke
				(width 0)
				(type default)
			)
			(fill no)
			(layer "F.Fab")
		)
		(pad "1" smd custom
			(at 0 -0.4445 90)
			(size 0.1397 0.1397)
			(layers "F.Cu" "F.Mask" "F.Paste")
			(net "P3V3_STBY")
			(options
				(clearance outline)
				(anchor circle)
			)
			(primitives
				(gr_poly
					(pts
						(arc
							(start -0.1778 -0.2794)
							(mid -0.249642 -0.249642)
							(end -0.2794 -0.1778)
						)
						(arc
							(start -0.2794 0.1778)
							(mid -0.249642 0.249642)
							(end -0.1778 0.2794)
						)
						(arc
							(start 0.1778 0.2794)
							(mid 0.249642 0.249642)
							(end 0.2794 0.1778)
						)
						(arc
							(start 0.2794 -0.1778)
							(mid 0.249642 -0.249642)
							(end 0.1778 -0.2794)
						)
					)
					(width 0)
					(fill yes)
				)
			)
		)
		(pad "2" smd custom
			(at 0 0.4445 90)
			(size 0.1397 0.1397)
			(layers "F.Cu" "F.Mask" "F.Paste")
			(net "LED_R_3")
			(options
				(clearance outline)
				(anchor circle)
			)
			(primitives
				(gr_poly
					(pts
						(arc
							(start -0.1778 -0.2794)
							(mid -0.249642 -0.249642)
							(end -0.2794 -0.1778)
						)
						(arc
							(start -0.2794 0.1778)
							(mid -0.249642 0.249642)
							(end -0.1778 0.2794)
						)
						(arc
							(start 0.1778 0.2794)
							(mid 0.249642 0.249642)
							(end 0.2794 0.1778)
						)
						(arc
							(start 0.2794 -0.1778)
							(mid 0.249642 -0.249642)
							(end 0.1778 -0.2794)
						)
					)
					(width 0)
					(fill yes)
				)
			)
		)
	)
	(footprint ""
		(layer "F.Cu")
		(at 25.2984 -69.088 90)
		(property "Reference" "R2948"
			(at 0 0 90)
			(layer "F.SilkS")
			(hide yes)
			(effects
				(font
					(size 1.27 1.27)
				)
			)
		)
		(property "Value" "0R2J-2-GP"
			(at 0.064008 -3.993896 90)
			(unlocked yes)
			(layer "F.Fab")
			(hide yes)
			(effects
				(font
					(size 1.016 1.016)
					(thickness 0.1524)
				)
			)
		)
		(property "Device Type" "R402H16"
			(at 0.064008 -5.517896 90)
			(unlocked yes)
			(layer "F.Fab")
			(hide yes)
			(effects
				(font
					(size 1.016 1.016)
					(thickness 0.1524)
				)
			)
		)
		(duplicate_pad_numbers_are_jumpers no)
		(fp_line
			(start 0.508 -0.9398)
			(end -0.508 -0.9398)
			(stroke
				(width 0.1524)
				(type default)
			)
			(layer "F.SilkS")
		)
		(fp_line
			(start -0.508 -0.9398)
			(end -0.508 0.9398)
			(stroke
				(width 0.1524)
				(type default)
			)
			(layer "F.SilkS")
		)
		(fp_rect
			(start -0.508 0.9398)
			(end 0.508 -0.9398)
			(stroke
				(width 0)
				(type default)
			)
			(fill no)
			(layer "F.CrtYd")
		)
		(fp_rect
			(start -0.508 0.9398)
			(end 0.508 -0.9398)
			(stroke
				(width 0)
				(type default)
			)
			(fill no)
			(layer "F.Fab")
		)
		(pad "1" smd custom
			(at 0 -0.4445 90)
			(size 0.1397 0.1397)
			(layers "F.Cu" "F.Mask" "F.Paste")
			(net "BMC_I2C5_D_PEB_DEVICE_SCL")
			(options
				(clearance outline)
				(anchor circle)
			)
			(primitives
				(gr_poly
					(pts
						(arc
							(start -0.1778 -0.2794)
							(mid -0.249642 -0.249642)
							(end -0.2794 -0.1778)
						)
						(arc
							(start -0.2794 0.1778)
							(mid -0.249642 0.249642)
							(end -0.1778 0.2794)
						)
						(arc
							(start 0.1778 0.2794)
							(mid 0.249642 0.249642)
							(end 0.2794 0.1778)
						)
						(arc
							(start 0.2794 -0.1778)
							(mid 0.249642 -0.249642)
							(end 0.1778 -0.2794)
						)
					)
					(width 0)
					(fill yes)
				)
			)
		)
		(pad "2" smd custom
			(at 0 0.4445 90)
			(size 0.1397 0.1397)
			(layers "F.Cu" "F.Mask" "F.Paste")
			(net "I2C_TPM_SCL")
			(options
				(clearance outline)
				(anchor circle)
			)
			(primitives
				(gr_poly
					(pts
						(arc
							(start -0.1778 -0.2794)
							(mid -0.249642 -0.249642)
							(end -0.2794 -0.1778)
						)
						(arc
							(start -0.2794 0.1778)
							(mid -0.249642 0.249642)
							(end -0.1778 0.2794)
						)
						(arc
							(start 0.1778 0.2794)
							(mid 0.249642 0.249642)
							(end 0.2794 0.1778)
						)
						(arc
							(start 0.2794 -0.1778)
							(mid 0.249642 -0.249642)
							(end 0.1778 -0.2794)
						)
					)
					(width 0)
					(fill yes)
				)
			)
		)
	)
	(footprint ""
		(layer "F.Cu")
		(at 86.548214 -83.04022 -90)
		(property "Reference" "U187"
			(at 0 0 270)
			(layer "F.SilkS")
			(hide yes)
			(effects
				(font
					(size 1.27 1.27)
				)
			)
		)
		(property "Value" "TXS0102DCUR-1-GP"
			(at 0 -11.1252 270)
			(unlocked yes)
			(layer "F.Fab")
			(hide yes)
			(effects
				(font
					(size 1.016 1.016)
					(thickness 0.1524)
				)
			)
		)
		(property "Device Type" "SSOIC8-4H36"
			(at 0 -12.6492 270)
			(unlocked yes)
			(layer "F.Fab")
			(hide yes)
			(effects
				(font
					(size 1.016 1.016)
					(thickness 0.1524)
				)
			)
		)
		(duplicate_pad_numbers_are_jumpers no)
		(fp_line
			(start -1.2573 2.1844)
			(end -1.2573 -2.1844)
			(stroke
				(width 0.1524)
				(type default)
			)
			(layer "F.SilkS")
		)
		(fp_line
			(start 1.2573 2.1844)
			(end -1.2573 2.1844)
			(stroke
				(width 0.1524)
				(type default)
			)
			(layer "F.SilkS")
		)
		(fp_line
			(start -1.2954 0.4572)
			(end -1.2954 2.159)
			(stroke
				(width 0.4064)
				(type default)
			)
			(layer "F.SilkS")
		)
		(fp_line
			(start -1.2065 0.2667)
			(end -1.27 0.2667)
			(stroke
				(width 0.1524)
				(type default)
			)
			(layer "F.SilkS")
		)
		(fp_line
			(start -0.9017 -0.0381)
			(end -1.2065 0.2667)
			(stroke
				(width 0.1524)
				(type default)
			)
			(layer "F.SilkS")
		)
		(fp_line
			(start -1.2573 -0.3556)
			(end -1.2192 -0.3556)
			(stroke
				(width 0.1524)
				(type default)
			)
			(layer "F.SilkS")
		)
		(fp_line
			(start -1.2192 -0.3556)
			(end -0.9017 -0.0381)
			(stroke
				(width 0.1524)
				(type default)
			)
			(layer "F.SilkS")
		)
		(fp_line
			(start -1.2573 -2.1844)
			(end 1.2573 -2.1844)
			(stroke
				(width 0.1524)
				(type default)
			)
			(layer "F.SilkS")
		)
		(fp_line
			(start 1.2573 -2.1844)
			(end 1.2573 2.1844)
			(stroke
				(width 0.1524)
				(type default)
			)
			(layer "F.SilkS")
		)
		(fp_poly
			(pts
				(xy -1.5113 2.4384) (xy 1.5113 2.4384) (xy 1.5113 -2.4384) (xy -1.5113 -2.4384)
			)
			(stroke
				(width 0)
				(type default)
			)
			(fill no)
			(layer "F.CrtYd")
		)
		(fp_poly
			(pts
				(xy -1.5113 -2.4384) (xy 1.5113 -2.4384) (xy 1.5113 2.4384) (xy -1.5113 2.4384)
			)
			(stroke
				(width 0)
				(type default)
			)
			(fill no)
			(layer "F.Fab")
		)
		(pad "1" smd rect
			(at -0.75057 1.1684 270)
			(size 0.3048 1.524)
			(layers "F.Cu" "F.Mask" "F.Paste")
			(net "EXP_SMART_RX_R")
		)
		(pad "2" smd rect
			(at -0.25019 1.1684 270)
			(size 0.3048 1.524)
			(layers "F.Cu" "F.Mask" "F.Paste")
			(net "GND")
		)
		(pad "3" smd rect
			(at 0.25019 1.1684 270)
			(size 0.3048 1.524)
			(layers "F.Cu" "F.Mask" "F.Paste")
			(net "P1V8_STBY")
		)
		(pad "4" smd rect
			(at 0.75057 1.1684 270)
			(size 0.3048 1.524)
			(layers "F.Cu" "F.Mask" "F.Paste")
			(net "SAS_SMART_R_RX")
		)
		(pad "5" smd rect
			(at 0.75057 -1.1684 270)
			(size 0.3048 1.524)
			(layers "F.Cu" "F.Mask" "F.Paste")
			(net "SAS_SMART_R_TX")
		)
		(pad "6" smd rect
			(at 0.25019 -1.1684 270)
			(size 0.3048 1.524)
			(layers "F.Cu" "F.Mask" "F.Paste")
			(net "SMART_UART_EN")
		)
		(pad "7" smd rect
			(at -0.25019 -1.1684 270)
			(size 0.3048 1.524)
			(layers "F.Cu" "F.Mask" "F.Paste")
			(net "P3V3_STBY")
		)
		(pad "8" smd rect
			(at -0.75057 -1.1684 270)
			(size 0.3048 1.524)
			(layers "F.Cu" "F.Mask" "F.Paste")
			(net "EXP_SMART_TX_R")
		)
	)
	(footprint ""
		(layer "F.Cu")
		(at 153.101802 -61.177932 -90)
		(property "Reference" "PU1"
			(at 0 0 270)
			(layer "F.SilkS")
			(hide yes)
			(effects
				(font
					(size 1.27 1.27)
				)
			)
		)
		(property "Value" "TPS53355ADQPR-GP"
			(at 4.7498 -5.6896 270)
			(unlocked yes)
			(layer "F.Fab")
			(hide yes)
			(effects
				(font
					(size 1.016 1.016)
					(thickness 0.1524)
				)
			)
		)
		(property "Device Type" "QFN22G6050-G6133H60"
			(at 4.7498 -7.2136 270)
			(unlocked yes)
			(layer "F.Fab")
			(hide yes)
			(effects
				(font
					(size 1.016 1.016)
					(thickness 0.1524)
				)
			)
		)
		(duplicate_pad_numbers_are_jumpers no)
		(fp_line
			(start -3.556 3.5179)
			(end -2.286 3.5179)
			(stroke
				(width 0.1524)
				(type default)
			)
			(layer "F.SilkS")
		)
		(fp_line
			(start 2.286 3.5179)
			(end 3.556 3.5179)
			(stroke
				(width 0.1524)
				(type default)
			)
			(layer "F.SilkS")
		)
		(fp_line
			(start 3.556 3.5179)
			(end 3.556 2.2479)
			(stroke
				(width 0.1524)
				(type default)
			)
			(layer "F.SilkS")
		)
		(fp_line
			(start -0.999998 3.262122)
			(end -0.999998 3.770122)
			(stroke
				(width 0.1524)
				(type default)
			)
			(layer "F.SilkS")
		)
		(fp_line
			(start 1.500124 3.262122)
			(end 1.500124 4.024122)
			(stroke
				(width 0.1524)
				(type default)
			)
			(layer "F.SilkS")
		)
		(fp_line
			(start -3.556 2.2479)
			(end -3.556 3.5179)
			(stroke
				(width 0.1524)
				(type default)
			)
			(layer "F.SilkS")
		)
		(fp_line
			(start -1.999996 -3.262122)
			(end -1.999996 -4.024122)
			(stroke
				(width 0.1524)
				(type default)
			)
			(layer "F.SilkS")
		)
		(fp_line
			(start 0.500126 -3.262122)
			(end 0.500126 -3.770122)
			(stroke
				(width 0.1524)
				(type default)
			)
			(layer "F.SilkS")
		)
		(fp_line
			(start -3.556 -3.5179)
			(end -3.556 -2.2479)
			(stroke
				(width 0.1524)
				(type default)
			)
			(layer "F.SilkS")
		)
		(fp_line
			(start -2.286 -3.5179)
			(end -3.556 -3.5179)
			(stroke
				(width 0.1524)
				(type default)
			)
			(layer "F.SilkS")
		)
		(fp_poly
			(pts
				(xy 3.556 -3.5179) (xy 2.5273 -3.5179) (xy 3.556 -2.4892)
			)
			(stroke
				(width 0)
				(type default)
			)
			(fill yes)
			(layer "F.SilkS")
		)
		(fp_rect
			(start -2.9972 2.5019)
			(end 2.9972 -2.5019)
			(stroke
				(width 0)
				(type default)
			)
			(fill no)
			(layer "F.CrtYd")
		)
		(fp_poly
			(pts
				(xy 3.556 -2.5019) (xy -2.9972 -2.5019) (xy -2.9972 2.5019) (xy 2.9972 2.5019) (xy 2.9972 -2.4892)
				(xy 3.556 -2.4892) (xy 3.556 3.5179) (xy -3.556 3.5179) (xy -3.556 -3.5179) (xy 3.556 -3.5179)
			)
			(stroke
				(width 0)
				(type default)
			)
			(fill no)
			(layer "F.CrtYd")
		)
		(fp_rect
			(start -3.556 3.5179)
			(end 3.556 -3.5179)
			(stroke
				(width 0)
				(type default)
			)
			(fill no)
			(layer "F.Fab")
		)
		(pad "1" smd rect
			(at 2.500122 -2.449322 270)
			(size 0.3048 1.1176)
			(layers "F.Cu" "F.Mask" "F.Paste")
			(net "P0V9_VFB")
		)
		(pad "2" smd rect
			(at 1.999996 -2.449322 270)
			(size 0.3048 1.1176)
			(layers "F.Cu" "F.Mask" "F.Paste")
			(net "P0V9_EN")
		)
		(pad "3" smd rect
			(at 1.500124 -2.449322 270)
			(size 0.3048 1.1176)
			(layers "F.Cu" "F.Mask" "F.Paste")
			(net "P0V9_PG")
		)
		(pad "4" smd rect
			(at 0.999998 -2.449322 270)
			(size 0.3048 1.1176)
			(layers "F.Cu" "F.Mask" "F.Paste")
			(net "P0V9_VBST")
		)
		(pad "5" smd rect
			(at 0.500126 -2.449322 270)
			(size 0.3048 1.1176)
			(layers "F.Cu" "F.Mask" "F.Paste")
			(net "Net_2122")
		)
		(pad "6" smd rect
			(at 0 -2.449322 270)
			(size 0.3048 1.1176)
			(layers "F.Cu" "F.Mask" "F.Paste")
			(net "P0V9_LX")
		)
		(pad "7" smd rect
			(at -0.500126 -2.449322 270)
			(size 0.3048 1.1176)
			(layers "F.Cu" "F.Mask" "F.Paste")
			(net "P0V9_LX")
		)
		(pad "8" smd rect
			(at -0.999998 -2.449322 270)
			(size 0.3048 1.1176)
			(layers "F.Cu" "F.Mask" "F.Paste")
			(net "P0V9_LX")
		)
		(pad "9" smd rect
			(at -1.500124 -2.449322 270)
			(size 0.3048 1.1176)
			(layers "F.Cu" "F.Mask" "F.Paste")
			(net "P0V9_LX")
		)
		(pad "10" smd rect
			(at -1.999996 -2.449322 270)
			(size 0.3048 1.1176)
			(layers "F.Cu" "F.Mask" "F.Paste")
			(net "P0V9_LX")
		)
		(pad "11" smd rect
			(at -2.500122 -2.449322 270)
			(size 0.3048 1.1176)
			(layers "F.Cu" "F.Mask" "F.Paste")
			(net "P0V9_LX")
		)
		(pad "12" smd rect
			(at -2.500122 2.449322 270)
			(size 0.3048 1.1176)
			(layers "F.Cu" "F.Mask" "F.Paste")
			(net "P0V9_VIN")
		)
		(pad "13" smd rect
			(at -1.999996 2.449322 270)
			(size 0.3048 1.1176)
			(layers "F.Cu" "F.Mask" "F.Paste")
			(net "P0V9_VIN")
		)
		(pad "14" smd rect
			(at -1.500124 2.449322 270)
			(size 0.3048 1.1176)
			(layers "F.Cu" "F.Mask" "F.Paste")
			(net "P0V9_VIN")
		)
		(pad "15" smd rect
			(at -0.999998 2.449322 270)
			(size 0.3048 1.1176)
			(layers "F.Cu" "F.Mask" "F.Paste")
			(net "P0V9_VIN")
		)
		(pad "16" smd rect
			(at -0.500126 2.449322 270)
			(size 0.3048 1.1176)
			(layers "F.Cu" "F.Mask" "F.Paste")
			(net "P0V9_VIN")
		)
		(pad "17" smd rect
			(at 0 2.449322 270)
			(size 0.3048 1.1176)
			(layers "F.Cu" "F.Mask" "F.Paste")
			(net "P0V9_VIN")
		)
		(pad "18" smd rect
			(at 0.500126 2.449322 270)
			(size 0.3048 1.1176)
			(layers "F.Cu" "F.Mask" "F.Paste")
			(net "P0V9_VREG")
		)
		(pad "19" smd rect
			(at 0.999998 2.449322 270)
			(size 0.3048 1.1176)
			(layers "F.Cu" "F.Mask" "F.Paste")
			(net "P0V9_VDD")
		)
		(pad "20" smd rect
			(at 1.500124 2.449322 270)
			(size 0.3048 1.1176)
			(layers "F.Cu" "F.Mask" "F.Paste")
			(net "P0V9_MODE")
		)
		(pad "21" smd rect
			(at 1.999996 2.449322 270)
			(size 0.3048 1.1176)
			(layers "F.Cu" "F.Mask" "F.Paste")
			(net "P0V9_TRIP")
		)
		(pad "22" smd rect
			(at 2.500122 2.449322 270)
			(size 0.3048 1.1176)
			(layers "F.Cu" "F.Mask" "F.Paste")
			(net "P0V9_RF")
		)
		(pad "23" smd custom
			(at 0 0 270)
			(size 0.83185 0.83185)
			(layers "F.Cu" "F.Mask" "F.Paste")
			(net "GND")
			(options
				(clearance outline)
				(anchor circle)
			)
			(primitives
				(gr_poly
					(pts
						(xy -2.7813 1.6637) (xy -2.7813 1.2954) (xy -3.048 1.2954) (xy -3.048 0.9525) (xy -2.7813 0.9525)
						(xy -2.7813 -0.9525) (xy -3.048 -0.9525) (xy -3.048 -1.2954) (xy -2.7813 -1.2954) (xy -2.7813 -1.6637)
						(xy 2.7813 -1.6637) (xy 2.7813 -1.2954) (xy 3.048 -1.2954) (xy 3.048 -0.9525) (xy 2.7813 -0.9525)
						(xy 2.7813 0.9525) (xy 3.048 0.9525) (xy 3.048 1.2954) (xy 2.7813 1.2954) (xy 2.7813 1.6637)
					)
					(width 0)
					(fill yes)
				)
			)
		)
	)
)
